# Primary and Alternate BOM of B91.01110.0017_LED.xls — Sheet0 (bom)
| Part Number | B91.01110.0017 |  |  |  |  |  |  |  |  |  |  |  |  |
| Revision | B |  |  |  |  |  |  |  |  |  |  |  |  |
| Sequence | 1 |  |  |  |  |  |  |  |  |  |  |  |  |
| Description | BRYCE CANYON LED GCE-1 PD-P MAIN |  |  |  |  |  |  |  |  |  |  |  |  |
| Project Code | BPD011010001 |  |  |  |  |  |  |  |  |  |  |  |  |
| Latest Revision? | YES |  |  |  |  |  |  |  |  |  |  |  |  |
| PDM BOM List |  |  |  |  |  |  |  |  |  |  |  |  |  |
| Level | Parent Number | Part Number | Description | Green Factor | Manufacturer | Manufacturer Part Number | Source | BOM Usage | M/P Code | S/D | Qty | UoM | Location |
| 1 | B91.01110.0017 | B55.01108.0002 | BRYCE CANYON LED GCE-1 PD-P MAIN(D) | R2; |  |  |  | M | Manufacture |  | 1 | PCS |  |
| 2 | B55.01108.0002 | 40.58D03.001 | LBL POLYIMIDE31.8*6.35 BARCODE | R2_SA;HF_SA;G_SA; | LABELJET | 40.58D03.001 | Single |  | Purchase | DIP | 1 | PCS |  |
| 2 | B55.01108.0002 | 640.00X01.0001 | LBL 7X7MM  FOR SONIC | R2_SA;HF_SA; | WISTRON | 640.00X01.0001 | Single |  | Purchase | DIP | 1 | PCS |  |
| 2 | B55.01108.0002 | B55.01108.M002 | BRYCE CANYON LED GCE-1 PD-P MAIN(S) | R2; |  |  |  | M | Manufacture | DIP | 1 | PCS |  |
| 3 | B55.01108.M002 | 020.F0496.0020 | CONN WTB 20P G846A20120T1HR SMD MP ,NY9T | R2_SA;HF_SA; | AMPHENOL | G846A20120T1HR | Single |  | Purchase | SMT | 1 | PCS | CN1 |
| 3 | B55.01108.M002 | 083.00195.0B70 | LED B/Y LTST-C195TBJSKTINV SMD | R2_SA;HF_SA; | LITEON | LTST-C195TBJSKTINV | Multiple |  | Purchase | SMT | 6 | PCS | LED1 LED2 LED3 LED4 LED5 LED6 |
| A(Alternative to previous component) | B55.01108.M002 | 83.19223.H70 | LED Y/B 19-223/Y2BHC-C01/2TSM | R2_SA;HF_SA; | EVERLIGHT | 19-223/Y2BHC-C01/2T |  |  | Purchase |  |  |  |  |
| 3 | B55.01108.M002 | 084.3K324.0031 | FET MOS NC SSM3K324R SOT-23F 3P | R2_SA;HF_SA; | TOSHIBA | SSM3K324R | Multiple |  | Purchase | SMT | 6 | PCS | Q10 Q12 Q2 Q4 Q6 Q8 |
| A | B55.01108.M002 | 084.06244.0031 | FET MOS IRLML6244TRPBF SOT-23 | R2_SA;HF_SA; | IR | IRLML6244TRPBF |  |  | Purchase |  |  |  |  |
| 3 | B55.01108.M002 | 64.13005.55L | CHIP RES 130 F 1/10W 0603 | R2_SA;HF_SA;G_SA; | TA-I ; RALEC ; YAGEO | RM06FTN1300 ; RTT031300FTP ; RC0603FR-07130RL | Multiple |  | Purchase | SMT | 6 | PCS | R1 R11 R3 R5 R7 R9 |
| 3 | B55.01108.M002 | 64.47015.6DL | CHIP RES 4.7K F 1/16W 0402 | R2_SA;HF_SA;G_SA; | TA-I;RALEC;CYNTEC;YAGEO;WALSIN | RM04FTN4701;RTT024701FTH;RR0510S-472-FN;RC0402FR-074K7L;WR04X4701FTL | Multiple |  | Purchase | SMT | 12 | PCS | R13 R14 R15 R16 R17 R18 R19 R20 R21 R22 R23 R24 |
| 3 | B55.01108.M002 | 64.91R05.55L | CHIP RES 91 F 1/10W 0603 | R2_SA;HF_SA;G_SA; | TA-I ; RALEC ; YAGEO | RM06FTN91R0 ; RTT0391R0FTP ; RC0603FR-0791RL | Multiple |  | Purchase | SMT | 6 | PCS | R10 R12 R2 R4 R6 R8 |
| 3 | B55.01108.M002 | 78.10521.2BL | CHIP CAP C 1U 16V K0603 X7R | R2_SA;HF_SA;G_SA; | KEMET;MURATA;TAIYO;TDK;YAGEO;WALSIN;SAMSUNG;DARFON | C0603C105K4RAC;GRM188R71C105KA12D;EMK107B7105KA-T;C1608X7R1C105KT;CC0603KRX7R7BB105;0603B105K160CT;CL10B105KO8NNNC;C1608X7R105KET | Multiple |  | Purchase | SMT | 1 | PCS | C1 |
| 3 | B55.01108.M002 | 78.10621.22L | CHIP CAP C 10U 16V K1206 X7R | R2_SA;HF_SA;G_SA; | MURATA;TDK;AVX;DARFON;SAMSUNG;TAIYO;WALSIN | GRM31CR71C106KA12L;C3216X7R1C106KT;CM316X7R106K16AT;C3216X7R106KEP;CL31B106KOHNNNE;EMK316B7106KL-T;1206B106K160CT | Multiple |  | Purchase | SMT | 1 | PCS | C2 |
| 3 | B55.01108.M002 | 84.2N702.J31 | FET MOS 2N7002K NC SOT-23 ESD 2KV 300MA | R2_SA;HF_SA;G_SA; | PANJIT | 2N7002K | Multiple |  | Purchase | SMT | 6 | PCS | Q1 Q11 Q3 Q5 Q7 Q9 |
| A | B55.01108.M002 | 084.27002.0L31 | FET MOS T2N7002BK NC SOT-23 | R2_SA;HF_SA; | TOSHIBA | T2N7002BK |  |  | Purchase |  |  |  |  |
| 3 | B55.01108.M002 | B48.01135.0011 | PCB 16347-1 BRYCE CANYON LED BOARD 2L GC | R2_SA;HF_SA; | GCE | B48.01135.0011 | Multiple |  | Purchase | SMT | 1 | PCS |  |
| A | B55.01108.M002 | B48.01150.0011 | PCB 16347-1 BRYCE CANYON LED BOARD 2L TR | R2_SA;HF_SA; | TRIPOD | B48.01150.0011 |  |  | Purchase |  |  |  |  |
